# S9S_MB_2U (Grand Teton) — schematic netlist excerpt (pin names and nets, part order shuffled) for the footprints in the layout excerpt that follows; sources: Cadence DE-HDL packaged netlist, KiCad conversion of 03242023_DA0F0TMBIJ0_F0T_Motherboard_J_brd_V01_OCP.brd

C448  Q_CAP  47UF 4V 20% X6S  pkg C0805  page 78 : A = PVCCFA_EHV_CPU1 ; B = GND
PR155  Q_RES  0 5% CHIP  pkg 0402LF  page 267 : A = PVCCIN_CPU0_VOS1 ; B = PVCCIN_CPU0
PC610_P0_1  Q_CAP  22UF 16V 20% X6S  pkg C0805  page 271 : A = SW_P12V_PVCCFA_EHV_FIVRA_CPU0_R ; B = GND

(kicad_pcb
	(version 20260206)
	(generator "pcbnew")
	(generator_version "10.0")
	(general
		(thickness 1.6)
		(legacy_teardrops no)
	)
	(paper "A4")
	(title_block
		(title "03242023_DA0F0TMBIJ0_F0T_Motherboard_J_brd_V01_OCP.brd")
		(comment 1 "Grand Teton / footprints 4449-4451 of 6105")
	)
	(layers
		(0 "F.Cu" signal "TOP")
		(4 "In1.Cu" signal "GND")
		(6 "In2.Cu" signal "IN1")
		(8 "In3.Cu" signal "GND1")
		(10 "In4.Cu" signal "IN2")
		(12 "In5.Cu" signal "GND2")
		(14 "In6.Cu" signal "IN3")
		(16 "In7.Cu" signal "GND3")
		(18 "In8.Cu" signal "VCC")
		(20 "In9.Cu" signal "VCC1")
		(22 "In10.Cu" signal "GND4")
		(24 "In11.Cu" signal "IN4")
		(26 "In12.Cu" signal "GND5")
		(28 "In13.Cu" signal "IN5")
		(30 "In14.Cu" signal "GND6")
		(32 "In15.Cu" signal "IN6")
		(34 "In16.Cu" signal "GND7")
		(2 "B.Cu" signal "BOTTOM")
		(9 "F.Adhes" user "F.Adhesive")
		(11 "B.Adhes" user "B.Adhesive")
		(13 "F.Paste" user "Package Geometry/Pastemask Top")
		(15 "B.Paste" user "Package Geometry/Pastemask Bottom")
		(5 "F.SilkS" user "Ref Des/Silkscreen Top")
		(7 "B.SilkS" user "Ref Des/Silkscreen Bottom")
		(1 "F.Mask" user "Board Geometry/Soldermask Top")
		(3 "B.Mask" user "Board Geometry/Soldermask Bottom")
		(17 "Dwgs.User" user "User.Drawings")
		(19 "Cmts.User" user "User.Comments")
		(21 "Eco1.User" user "User.Eco1")
		(23 "Eco2.User" user "User.Eco2")
		(25 "Edge.Cuts" user "Board Geometry/Outline")
		(27 "Margin" user)
		(31 "F.CrtYd" user "Package Geometry/Place Bound Top")
		(29 "B.CrtYd" user "Package Geometry/Place Bound Bottom")
		(35 "F.Fab" user "Ref Des/Assembly Top")
		(33 "B.Fab" user "Ref Des/Assembly Bottom")
	)
	(footprint ""
		(layer "B.Cu")
		(at 417.282122 -362.107226 90)
		(property "Reference" "PC610_P0_1"
			(at 0 0 90)
			(layer "B.SilkS")
			(hide yes)
			(effects
				(font
					(size 1.27 1.27)
				)
				(justify mirror)
			)
		)
		(property "Value" ""
			(at 0 0 90)
			(layer "B.Fab")
			(effects
				(font
					(size 1.27 1.27)
				)
				(justify mirror)
			)
		)
		(duplicate_pad_numbers_are_jumpers no)
		(fp_line
			(start 1.524 -0.762)
			(end -1.524 -0.762)
			(stroke
				(width 0.1524)
				(type default)
			)
			(layer "B.SilkS")
		)
		(fp_line
			(start -1.524 -0.762)
			(end -1.524 0.762)
			(stroke
				(width 0.1524)
				(type default)
			)
			(layer "B.SilkS")
		)
		(fp_line
			(start 1.524 0.762)
			(end 1.524 -0.762)
			(stroke
				(width 0.1524)
				(type default)
			)
			(layer "B.SilkS")
		)
		(fp_line
			(start -1.524 0.762)
			(end 1.524 0.762)
			(stroke
				(width 0.1524)
				(type default)
			)
			(layer "B.SilkS")
		)
		(fp_line
			(start 1.1049 -0.724916)
			(end 1.1049 0.724916)
			(stroke
				(width 0.1)
				(type default)
			)
			(layer "B.Fab")
		)
		(fp_line
			(start -1.1049 -0.724916)
			(end 1.1049 -0.724916)
			(stroke
				(width 0.1)
				(type default)
			)
			(layer "B.Fab")
		)
		(fp_line
			(start 1.1049 0.724916)
			(end -1.1049 0.724916)
			(stroke
				(width 0.1)
				(type default)
			)
			(layer "B.Fab")
		)
		(fp_line
			(start -1.1049 0.724916)
			(end -1.1049 -0.724916)
			(stroke
				(width 0.1)
				(type default)
			)
			(layer "B.Fab")
		)
		(pad "1" smd rect
			(at 0.889 0 90)
			(size 1.016 1.27)
			(layers "B.Cu" "B.Mask" "B.Paste")
			(net "SW_P12V_PVCCFA_EHV_FIVRA_CPU0_R")
		)
		(pad "2" smd rect
			(at -0.889 0 90)
			(size 1.016 1.27)
			(layers "B.Cu" "B.Mask" "B.Paste")
			(net "GND")
		)
	)
	(footprint ""
		(layer "B.Cu")
		(at 103.901494 -259.533136 -90)
		(property "Reference" "C448"
			(at 0 0 90)
			(layer "B.SilkS")
			(hide yes)
			(effects
				(font
					(size 1.27 1.27)
				)
				(justify mirror)
			)
		)
		(property "Value" ""
			(at 0 0 90)
			(layer "B.Fab")
			(effects
				(font
					(size 1.27 1.27)
				)
				(justify mirror)
			)
		)
		(duplicate_pad_numbers_are_jumpers no)
		(fp_line
			(start -1.524 0.762)
			(end 1.524 0.762)
			(stroke
				(width 0.1524)
				(type default)
			)
			(layer "B.SilkS")
		)
		(fp_line
			(start 1.524 0.762)
			(end 1.524 -0.762)
			(stroke
				(width 0.1524)
				(type default)
			)
			(layer "B.SilkS")
		)
		(fp_line
			(start -1.524 -0.762)
			(end -1.524 0.762)
			(stroke
				(width 0.1524)
				(type default)
			)
			(layer "B.SilkS")
		)
		(fp_line
			(start 1.524 -0.762)
			(end -1.524 -0.762)
			(stroke
				(width 0.1524)
				(type default)
			)
			(layer "B.SilkS")
		)
		(fp_line
			(start -1.1049 0.724916)
			(end -1.1049 -0.724916)
			(stroke
				(width 0.1)
				(type default)
			)
			(layer "B.Fab")
		)
		(fp_line
			(start 1.1049 0.724916)
			(end -1.1049 0.724916)
			(stroke
				(width 0.1)
				(type default)
			)
			(layer "B.Fab")
		)
		(fp_line
			(start -1.1049 -0.724916)
			(end 1.1049 -0.724916)
			(stroke
				(width 0.1)
				(type default)
			)
			(layer "B.Fab")
		)
		(fp_line
			(start 1.1049 -0.724916)
			(end 1.1049 0.724916)
			(stroke
				(width 0.1)
				(type default)
			)
			(layer "B.Fab")
		)
		(pad "1" smd rect
			(at 0.889 0 270)
			(size 1.016 1.27)
			(layers "B.Cu" "B.Mask" "B.Paste")
			(net "PVCCFA_EHV_CPU1")
		)
		(pad "2" smd rect
			(at -0.889 0 270)
			(size 1.016 1.27)
			(layers "B.Cu" "B.Mask" "B.Paste")
			(net "GND")
		)
	)
	(footprint ""
		(layer "B.Cu")
		(at 341.511128 -336.278474 -90)
		(property "Reference" "PR155"
			(at 0 0 90)
			(layer "B.SilkS")
			(hide yes)
			(effects
				(font
					(size 1.27 1.27)
				)
				(justify mirror)
			)
		)
		(property "Value" ""
			(at 0 0 90)
			(layer "B.Fab")
			(effects
				(font
					(size 1.27 1.27)
				)
				(justify mirror)
			)
		)
		(duplicate_pad_numbers_are_jumpers no)
		(fp_line
			(start -0.7874 0.4064)
			(end 0.7874 0.4064)
			(stroke
				(width 0.1524)
				(type default)
			)
			(layer "B.SilkS")
		)
		(fp_line
			(start 0.7874 0.4064)
			(end 0.7874 -0.4064)
			(stroke
				(width 0.1524)
				(type default)
			)
			(layer "B.SilkS")
		)
		(fp_line
			(start -0.7874 -0.4064)
			(end -0.7874 0.4064)
			(stroke
				(width 0.1524)
				(type default)
			)
			(layer "B.SilkS")
		)
		(fp_line
			(start 0.7874 -0.4064)
			(end -0.7874 -0.4064)
			(stroke
				(width 0.1524)
				(type default)
			)
			(layer "B.SilkS")
		)
		(fp_line
			(start -0.67945 0.3048)
			(end -0.120396 0.3048)
			(stroke
				(width 0.1)
				(type default)
			)
			(layer "B.Fab")
		)
		(fp_line
			(start -0.120396 0.3048)
			(end -0.120396 0.2794)
			(stroke
				(width 0.1)
				(type default)
			)
			(layer "B.Fab")
		)
		(fp_line
			(start 0.12065 0.3048)
			(end 0.67945 0.3048)
			(stroke
				(width 0.1)
				(type default)
			)
			(layer "B.Fab")
		)
		(fp_line
			(start 0.67945 0.3048)
			(end 0.67945 -0.305054)
			(stroke
				(width 0.1)
				(type default)
			)
			(layer "B.Fab")
		)
		(fp_line
			(start -0.120396 0.2794)
			(end 0.12065 0.2794)
			(stroke
				(width 0.1)
				(type default)
			)
			(layer "B.Fab")
		)
		(fp_line
			(start 0.12065 0.2794)
			(end 0.12065 0.3048)
			(stroke
				(width 0.1)
				(type default)
			)
			(layer "B.Fab")
		)
		(fp_line
			(start -0.12065 -0.2794)
			(end -0.12065 -0.3048)
			(stroke
				(width 0.1)
				(type default)
			)
			(layer "B.Fab")
		)
		(fp_line
			(start 0.12065 -0.2794)
			(end -0.12065 -0.2794)
			(stroke
				(width 0.1)
				(type default)
			)
			(layer "B.Fab")
		)
		(fp_line
			(start -0.67945 -0.3048)
			(end -0.67945 0.3048)
			(stroke
				(width 0.1)
				(type default)
			)
			(layer "B.Fab")
		)
		(fp_line
			(start -0.12065 -0.3048)
			(end -0.67945 -0.3048)
			(stroke
				(width 0.1)
				(type default)
			)
			(layer "B.Fab")
		)
		(fp_line
			(start 0.12065 -0.305054)
			(end 0.12065 -0.2794)
			(stroke
				(width 0.1)
				(type default)
			)
			(layer "B.Fab")
		)
		(fp_line
			(start 0.67945 -0.305054)
			(end 0.12065 -0.305054)
			(stroke
				(width 0.1)
				(type default)
			)
			(layer "B.Fab")
		)
		(pad "1" smd circle
			(at 0.40005 0 90)
			(size 0 0)
			(layers "B.Cu" "B.Mask" "B.Paste")
			(net "PVCCIN_CPU0_VOS1")
		)
		(pad "2" smd circle
			(at -0.40005 0 90)
			(size 0 0)
			(layers "B.Cu" "B.Mask" "B.Paste")
			(net "PVCCIN_CPU0")
		)
	)
)
